(kicad_pcb
	(version 20260206)
	(generator "pcbnew")
	(generator_version "10.0")
	(general
		(thickness 1.6)
		(legacy_teardrops no)
	)
	(paper "A4")
	(title_block
		(title "timecard-production-celestica-r4006 — R4006-B0001-02_R01.brd")
		(comment 1 "Time Appliance Project (Time Card) / footprints 536-537 of 1113")
	)
	(layers
		(0 "F.Cu" signal "TOP")
		(4 "In1.Cu" signal "L02_GND1")
		(6 "In2.Cu" signal "L03_SIG1")
		(8 "In3.Cu" signal "L04_GND2")
		(10 "In4.Cu" signal "L05_VCC1")
		(12 "In5.Cu" signal "L06_VCC2")
		(14 "In6.Cu" signal "L07_GND3")
		(16 "In7.Cu" signal "L08_SIG2")
		(18 "In8.Cu" signal "L09_GND4")
		(2 "B.Cu" signal "BOTTOM")
		(9 "F.Adhes" user "F.Adhesive")
		(11 "B.Adhes" user "B.Adhesive")
		(13 "F.Paste" user "Package Geometry/Pastemask Top")
		(15 "B.Paste" user "Package Geometry/Pastemask Bottom")
		(5 "F.SilkS" user "Ref Des/Silkscreen Top")
		(7 "B.SilkS" user "Ref Des/Silkscreen Bottom")
		(1 "F.Mask" user "Board Geometry/Soldermask Top")
		(3 "B.Mask" user "Board Geometry/Soldermask Bottom")
		(17 "Dwgs.User" user "User.Drawings")
		(19 "Cmts.User" user "User.Comments")
		(21 "Eco1.User" user "User.Eco1")
		(23 "Eco2.User" user "User.Eco2")
		(25 "Edge.Cuts" user "Board Geometry/Outline")
		(27 "Margin" user)
		(31 "F.CrtYd" user "Package Geometry/Place Bound Top")
		(29 "B.CrtYd" user "Package Geometry/Place Bound Bottom")
		(35 "F.Fab" user "Ref Des/Assembly Top")
		(33 "B.Fab" user "Ref Des/Assembly Bottom")
	)
	(footprint ""
		(layer "F.Cu")
		(at 54.61 -15.621 90)
		(property "Reference" "C288"
			(at 3.556 0.54737 90)
			(unlocked yes)
			(layer "F.SilkS")
			(effects
				(font
					(size 0.7874 0.5842)
					(thickness 0.1524)
				)
			)
		)
		(property "Value" "VAL*"
			(at 0.0762 2.067306 90)
			(unlocked yes)
			(layer "F.Fab")
			(hide yes)
			(effects
				(font
					(size 0.7874 0.5842)
					(thickness 0.1524)
				)
			)
		)
		(property "Device Type" "CAPACITOR-G105-0B104-EK,0.1UF,A"
			(at 0.0508 1.127506 90)
			(unlocked yes)
			(layer "F.Fab")
			(hide yes)
			(effects
				(font
					(size 0.7874 0.5842)
					(thickness 0.1524)
				)
			)
		)
		(property "User Part Number" "PARTNUM*"
			(at 0.1016 4.023106 90)
			(unlocked yes)
			(layer "Cmts.User")
			(hide yes)
			(effects
				(font
					(size 0.7874 0.5842)
					(thickness 0.1524)
				)
			)
		)
		(property "Tolerance" "TOL*"
			(at 0.0762 3.032506 90)
			(unlocked yes)
			(layer "Cmts.User")
			(hide yes)
			(effects
				(font
					(size 0.7874 0.5842)
					(thickness 0.1524)
				)
			)
		)
		(duplicate_pad_numbers_are_jumpers no)
		(fp_line
			(start 1.143 -0.5588)
			(end -1.143 -0.5588)
			(stroke
				(width 0.1)
				(type default)
			)
			(layer "F.SilkS")
		)
		(fp_line
			(start -1.143 -0.5588)
			(end -1.143 0.5588)
			(stroke
				(width 0.1)
				(type default)
			)
			(layer "F.SilkS")
		)
		(fp_line
			(start 1.143 0.5588)
			(end 1.143 -0.5588)
			(stroke
				(width 0.1)
				(type default)
			)
			(layer "F.SilkS")
		)
		(fp_line
			(start -1.143 0.5588)
			(end 1.143 0.5588)
			(stroke
				(width 0.1)
				(type default)
			)
			(layer "F.SilkS")
		)
		(fp_poly
			(pts
				(xy -1.143 0.5588) (xy 1.143 0.5588) (xy 1.143 -0.5588) (xy -1.143 -0.5588)
			)
			(stroke
				(width 0)
				(type default)
			)
			(fill no)
			(layer "F.CrtYd")
		)
		(fp_line
			(start 0.508 -0.3048)
			(end -0.508 -0.3048)
			(stroke
				(width 0.1)
				(type default)
			)
			(layer "F.Fab")
		)
		(fp_line
			(start -0.508 -0.3048)
			(end -0.508 0.3048)
			(stroke
				(width 0.1)
				(type default)
			)
			(layer "F.Fab")
		)
		(fp_line
			(start 0.508 0.3048)
			(end 0.508 -0.3048)
			(stroke
				(width 0.1)
				(type default)
			)
			(layer "F.Fab")
		)
		(fp_line
			(start -0.508 0.3048)
			(end 0.508 0.3048)
			(stroke
				(width 0.1)
				(type default)
			)
			(layer "F.Fab")
		)
		(pad "1" smd rect
			(at -0.5334 0 90)
			(size 0.7112 0.6096)
			(layers "F.Cu" "F.Mask" "F.Paste")
			(net "XP3R3V_AUX_PCIE")
		)
		(pad "2" smd rect
			(at 0.5334 0 90)
			(size 0.7112 0.6096)
			(layers "F.Cu" "F.Mask" "F.Paste")
			(net "SG")
		)
		(zone
			(layer "F.Cu")
			(hatch none 0.5)
			(connect_pads
				(clearance 0)
			)
			(min_thickness 0.25)
			(keepout
				(tracks not_allowed)
				(vias allowed)
				(pads allowed)
				(copperpour not_allowed)
				(footprints allowed)
			)
			(placement
				(enabled no)
				(sheetname "")
			)
			(fill
				(thermal_gap 0.5)
				(thermal_bridge_width 0.5)
				(island_removal_mode 0)
			)
			(polygon
				(pts
					(xy 54.9148 -15.5448) (xy 54.9148 -15.6972) (xy 54.3052 -15.6972) (xy 54.3052 -15.5448)
				)
			)
		)
		(zone
			(layer "F.Cu")
			(hatch none 0.5)
			(connect_pads
				(clearance 0)
			)
			(min_thickness 0.25)
			(keepout
				(tracks allowed)
				(vias not_allowed)
				(pads allowed)
				(copperpour not_allowed)
				(footprints allowed)
			)
			(placement
				(enabled no)
				(sheetname "")
			)
			(fill
				(thermal_gap 0.5)
				(thermal_bridge_width 0.5)
				(island_removal_mode 0)
			)
			(polygon
				(pts
					(xy 54.9148 -15.5448) (xy 54.9148 -15.6972) (xy 54.3052 -15.6972) (xy 54.3052 -15.5448)
				)
			)
		)
	)
	(footprint ""
		(layer "F.Cu")
		(at 115.062 -98.298 90)
		(property "Reference" "C81"
			(at 0.127 -1.35763 90)
			(unlocked yes)
			(layer "F.SilkS")
			(effects
				(font
					(size 0.7874 0.5842)
					(thickness 0.1524)
				)
			)
		)
		(property "Value" "VAL*"
			(at 0.0762 2.067306 90)
			(unlocked yes)
			(layer "F.Fab")
			(hide yes)
			(effects
				(font
					(size 0.7874 0.5842)
					(thickness 0.1524)
				)
			)
		)
		(property "Tolerance" "TOL*"
			(at 0.0762 3.032506 90)
			(unlocked yes)
			(layer "Cmts.User")
			(hide yes)
			(effects
				(font
					(size 0.7874 0.5842)
					(thickness 0.1524)
				)
			)
		)
		(property "User Part Number" "PARTNUM*"
			(at 0.1016 4.023106 90)
			(unlocked yes)
			(layer "Cmts.User")
			(hide yes)
			(effects
				(font
					(size 0.7874 0.5842)
					(thickness 0.1524)
				)
			)
		)
		(property "Device Type" "CAPACITOR-G105-0B104-CK,0.1UF,A"
			(at 0.0508 1.127506 90)
			(unlocked yes)
			(layer "F.Fab")
			(hide yes)
			(effects
				(font
					(size 0.7874 0.5842)
					(thickness 0.1524)
				)
			)
		)
		(duplicate_pad_numbers_are_jumpers no)
		(fp_line
			(start 1.143 -0.5588)
			(end -1.143 -0.5588)
			(stroke
				(width 0.1)
				(type default)
			)
			(layer "F.SilkS")
		)
		(fp_line
			(start -1.143 -0.5588)
			(end -1.143 0.5588)
			(stroke
				(width 0.1)
				(type default)
			)
			(layer "F.SilkS")
		)
		(fp_line
			(start 1.143 0.5588)
			(end 1.143 -0.5588)
			(stroke
				(width 0.1)
				(type default)
			)
			(layer "F.SilkS")
		)
		(fp_line
			(start -1.143 0.5588)
			(end 1.143 0.5588)
			(stroke
				(width 0.1)
				(type default)
			)
			(layer "F.SilkS")
		)
		(fp_rect
			(start -1.143 0.5588)
			(end 1.143 -0.5588)
			(stroke
				(width 0)
				(type default)
			)
			(fill no)
			(layer "F.CrtYd")
		)
		(fp_line
			(start 0.508 -0.3048)
			(end -0.508 -0.3048)
			(stroke
				(width 0.1)
				(type default)
			)
			(layer "F.Fab")
		)
		(fp_line
			(start -0.508 -0.3048)
			(end -0.508 0.3048)
			(stroke
				(width 0.1)
				(type default)
			)
			(layer "F.Fab")
		)
		(fp_line
			(start 0.508 0.3048)
			(end 0.508 -0.3048)
			(stroke
				(width 0.1)
				(type default)
			)
			(layer "F.Fab")
		)
		(fp_line
			(start -0.508 0.3048)
			(end 0.508 0.3048)
			(stroke
				(width 0.1)
				(type default)
			)
			(layer "F.Fab")
		)
		(pad "1" smd rect
			(at -0.5334 0 90)
			(size 0.7112 0.6096)
			(layers "F.Cu" "F.Mask" "F.Paste")
			(net "XP3R3V_FPGA")
		)
		(pad "2" smd rect
			(at 0.5334 0 90)
			(size 0.7112 0.6096)
			(layers "F.Cu" "F.Mask" "F.Paste")
			(net "SG")
		)
		(zone
			(layer "F.Cu")
			(hatch none 0.5)
			(connect_pads
				(clearance 0)
			)
			(min_thickness 0.25)
			(keepout
				(tracks allowed)
				(vias not_allowed)
				(pads allowed)
				(copperpour not_allowed)
				(footprints allowed)
			)
			(placement
				(enabled no)
				(sheetname "")
			)
			(fill
				(thermal_gap 0.5)
				(thermal_bridge_width 0.5)
				(island_removal_mode 0)
			)
			(polygon
				(pts
					(xy 115.3668 -98.2218) (xy 115.3668 -98.3742) (xy 114.7572 -98.3742) (xy 114.7572 -98.2218)
				)
			)
		)
	)
)
